# BASEBOARD_FAB2 (Tioga Pass) — schematic netlist excerpt (pin names and nets, part order shuffled) for the footprints in the layout excerpt that follows; sources: Cadence DE-HDL packaged netlist, KiCad conversion of Wiwynn_Tioga_Pass_MB.brd

C9G15  CAP  47.0PF 50V 5% COG  pkg 0402LF  page 169 : A = A_P5V_SCALED ; B = GND
R3N29  RES  16K 1.0% CHIP  pkg 0402  page 194 : A = VR_PVCCIOMCP_CPU0_XADDR1 ; B = GND
R5W2  RES  0.0 5% CHIP  pkg 0402  page 113 : A = P1V8_MCP_CPU1 ; B = JTAG_MCP_CPU1_TDI_R

(kicad_pcb
	(version 20260206)
	(generator "pcbnew")
	(generator_version "10.0")
	(general
		(thickness 1.6)
		(legacy_teardrops no)
	)
	(paper "A4")
	(title_block
		(title "Wiwynn_Tioga_Pass_MB.brd")
		(comment 1 "Tioga Pass / footprints 3815-3817 of 4770")
	)
	(layers
		(0 "F.Cu" signal "TOP")
		(4 "In1.Cu" signal "L2GND")
		(6 "In2.Cu" signal "L3")
		(8 "In3.Cu" signal "L4GND")
		(10 "In4.Cu" signal "L5")
		(12 "In5.Cu" signal "L6GND")
		(14 "In6.Cu" signal "L7VCC")
		(16 "In7.Cu" signal "L8VCC")
		(18 "In8.Cu" signal "L9GND")
		(20 "In9.Cu" signal "L10")
		(22 "In10.Cu" signal "L11GND")
		(24 "In11.Cu" signal "L12")
		(26 "In12.Cu" signal "L13GND")
		(2 "B.Cu" signal "BOTTOM")
		(9 "F.Adhes" user "F.Adhesive")
		(11 "B.Adhes" user "B.Adhesive")
		(13 "F.Paste" user "Package Geometry/Pastemask Top")
		(15 "B.Paste" user "Package Geometry/Pastemask Bottom")
		(5 "F.SilkS" user "Ref Des/Silkscreen Top")
		(7 "B.SilkS" user "Ref Des/Silkscreen Bottom")
		(1 "F.Mask" user "Board Geometry/Soldermask Top")
		(3 "B.Mask" user "Board Geometry/Soldermask Bottom")
		(17 "Dwgs.User" user "User.Drawings")
		(19 "Cmts.User" user "User.Comments")
		(21 "Eco1.User" user "User.Eco1")
		(23 "Eco2.User" user "User.Eco2")
		(25 "Edge.Cuts" user "Board Geometry/Outline")
		(27 "Margin" user)
		(31 "F.CrtYd" user "Package Geometry/Place Bound Top")
		(29 "B.CrtYd" user "Package Geometry/Place Bound Bottom")
		(35 "F.Fab" user "Ref Des/Assembly Top")
		(33 "B.Fab" user "Ref Des/Assembly Bottom")
	)
	(footprint ""
		(layer "B.Cu")
		(at 339.7504 -111.4044 180)
		(property "Reference" "R3N29"
			(at 0 0 0)
			(layer "B.SilkS")
			(hide yes)
			(effects
				(font
					(size 1.27 1.27)
				)
				(justify mirror)
			)
		)
		(property "Value" ""
			(at 0 0 0)
			(layer "B.Fab")
			(effects
				(font
					(size 1.27 1.27)
				)
				(justify mirror)
			)
		)
		(duplicate_pad_numbers_are_jumpers no)
		(fp_poly
			(pts
				(xy 0.2794 -0.1016) (xy -0.2794 -0.1016) (xy -0.2794 0.9906) (xy 0.2794 0.9906)
			)
			(stroke
				(width 0)
				(type default)
			)
			(fill no)
			(layer "B.CrtYd")
		)
		(fp_line
			(start 0.2794 0.9906)
			(end -0.2794 0.9906)
			(stroke
				(width 0.1)
				(type default)
			)
			(layer "B.Fab")
		)
		(fp_line
			(start 0.2794 -0.1016)
			(end 0.2794 0.9906)
			(stroke
				(width 0.1)
				(type default)
			)
			(layer "B.Fab")
		)
		(fp_line
			(start -0.2794 0.9906)
			(end -0.2794 -0.1016)
			(stroke
				(width 0.1)
				(type default)
			)
			(layer "B.Fab")
		)
		(fp_line
			(start -0.2794 -0.1016)
			(end 0.2794 -0.1016)
			(stroke
				(width 0.1)
				(type default)
			)
			(layer "B.Fab")
		)
		(pad "1" smd rect
			(at 0 0)
			(size 0.508 0.508)
			(layers "B.Cu" "B.Mask" "B.Paste")
			(net "VR_PVCCIOMCP_CPU0_XADDR1")
		)
		(pad "2" smd rect
			(at 0 0.889)
			(size 0.508 0.508)
			(layers "B.Cu" "B.Mask" "B.Paste")
			(net "GND")
		)
		(zone
			(layer "B.Cu")
			(hatch none 0.5)
			(connect_pads
				(clearance 0)
			)
			(min_thickness 0.25)
			(keepout
				(tracks not_allowed)
				(vias allowed)
				(pads allowed)
				(copperpour not_allowed)
				(footprints allowed)
			)
			(placement
				(enabled no)
				(sheetname "")
			)
			(fill
				(thermal_gap 0.5)
				(thermal_bridge_width 0.5)
				(island_removal_mode 0)
			)
			(polygon
				(pts
					(xy 339.4964 -112.0394) (xy 340.0044 -112.0394) (xy 340.0044 -111.6584) (xy 339.4964 -111.6584)
				)
			)
		)
		(zone
			(layer "B.Cu")
			(hatch none 0.5)
			(connect_pads
				(clearance 0)
			)
			(min_thickness 0.25)
			(keepout
				(tracks allowed)
				(vias not_allowed)
				(pads allowed)
				(copperpour not_allowed)
				(footprints allowed)
			)
			(placement
				(enabled no)
				(sheetname "")
			)
			(fill
				(thermal_gap 0.5)
				(thermal_bridge_width 0.5)
				(island_removal_mode 0)
			)
			(polygon
				(pts
					(xy 339.4964 -111.6584) (xy 340.0044 -111.6584) (xy 340.0044 -112.0394) (xy 339.4964 -112.0394)
				)
			)
		)
	)
	(footprint ""
		(layer "B.Cu")
		(at 171.059856 -128.850136)
		(property "Reference" "R5W2"
			(at 0.8382 -0.67818 0)
			(unlocked yes)
			(layer "B.SilkS")
			(effects
				(font
					(size 0.4064 0.254)
					(thickness 0.1524)
				)
				(justify left mirror)
			)
		)
		(property "Value" ""
			(at 0 0 0)
			(layer "B.Fab")
			(effects
				(font
					(size 1.27 1.27)
				)
				(justify mirror)
			)
		)
		(duplicate_pad_numbers_are_jumpers no)
		(fp_poly
			(pts
				(xy 0.2794 -0.1016) (xy -0.2794 -0.1016) (xy -0.2794 0.9906) (xy 0.2794 0.9906)
			)
			(stroke
				(width 0)
				(type default)
			)
			(fill no)
			(layer "B.CrtYd")
		)
		(fp_line
			(start -0.2794 -0.1016)
			(end 0.2794 -0.1016)
			(stroke
				(width 0.1)
				(type default)
			)
			(layer "B.Fab")
		)
		(fp_line
			(start -0.2794 0.9906)
			(end -0.2794 -0.1016)
			(stroke
				(width 0.1)
				(type default)
			)
			(layer "B.Fab")
		)
		(fp_line
			(start 0.2794 -0.1016)
			(end 0.2794 0.9906)
			(stroke
				(width 0.1)
				(type default)
			)
			(layer "B.Fab")
		)
		(fp_line
			(start 0.2794 0.9906)
			(end -0.2794 0.9906)
			(stroke
				(width 0.1)
				(type default)
			)
			(layer "B.Fab")
		)
		(pad "1" smd rect
			(at 0 0 180)
			(size 0.508 0.508)
			(layers "B.Cu" "B.Mask" "B.Paste")
			(net "P1V8_MCP_CPU1")
		)
		(pad "2" smd rect
			(at 0 0.889 180)
			(size 0.508 0.508)
			(layers "B.Cu" "B.Mask" "B.Paste")
			(net "JTAG_MCP_CPU1_TDI_R")
		)
		(zone
			(layer "B.Cu")
			(hatch none 0.5)
			(connect_pads
				(clearance 0)
			)
			(min_thickness 0.25)
			(keepout
				(tracks allowed)
				(vias not_allowed)
				(pads allowed)
				(copperpour not_allowed)
				(footprints allowed)
			)
			(placement
				(enabled no)
				(sheetname "")
			)
			(fill
				(thermal_gap 0.5)
				(thermal_bridge_width 0.5)
				(island_removal_mode 0)
			)
			(polygon
				(pts
					(xy 171.313856 -128.596136) (xy 170.805856 -128.596136) (xy 170.805856 -128.215136) (xy 171.313856 -128.215136)
				)
			)
		)
		(zone
			(layer "B.Cu")
			(hatch none 0.5)
			(connect_pads
				(clearance 0)
			)
			(min_thickness 0.25)
			(keepout
				(tracks not_allowed)
				(vias allowed)
				(pads allowed)
				(copperpour not_allowed)
				(footprints allowed)
			)
			(placement
				(enabled no)
				(sheetname "")
			)
			(fill
				(thermal_gap 0.5)
				(thermal_bridge_width 0.5)
				(island_removal_mode 0)
			)
			(polygon
				(pts
					(xy 171.313856 -128.215136) (xy 170.805856 -128.215136) (xy 170.805856 -128.596136) (xy 171.313856 -128.596136)
				)
			)
		)
	)
	(footprint ""
		(layer "B.Cu")
		(at 409.600146 -21.853652 -90)
		(property "Reference" "C9G15"
			(at 0 0 90)
			(layer "B.SilkS")
			(hide yes)
			(effects
				(font
					(size 1.27 1.27)
				)
				(justify mirror)
			)
		)
		(property "Value" ""
			(at 0 0 90)
			(layer "B.Fab")
			(effects
				(font
					(size 1.27 1.27)
				)
				(justify mirror)
			)
		)
		(duplicate_pad_numbers_are_jumpers no)
		(fp_poly
			(pts
				(xy -0.3048 -0.1016) (xy -0.3048 0.9906) (xy 0.3048 0.9906) (xy 0.3048 -0.1016)
			)
			(stroke
				(width 0)
				(type default)
			)
			(fill no)
			(layer "B.CrtYd")
		)
		(fp_line
			(start -0.3048 0.9906)
			(end -0.3048 -0.1016)
			(stroke
				(width 0.1)
				(type default)
			)
			(layer "B.Fab")
		)
		(fp_line
			(start 0.3048 0.9906)
			(end -0.3048 0.9906)
			(stroke
				(width 0.1)
				(type default)
			)
			(layer "B.Fab")
		)
		(fp_line
			(start -0.3048 -0.1016)
			(end 0.3048 -0.1016)
			(stroke
				(width 0.1)
				(type default)
			)
			(layer "B.Fab")
		)
		(fp_line
			(start 0.3048 -0.1016)
			(end 0.3048 0.9906)
			(stroke
				(width 0.1)
				(type default)
			)
			(layer "B.Fab")
		)
		(pad "1" smd rect
			(at 0 0 90)
			(size 0.508 0.508)
			(layers "B.Cu" "B.Mask" "B.Paste")
			(net "A_P5V_SCALED")
		)
		(pad "2" smd rect
			(at 0 0.889 90)
			(size 0.508 0.508)
			(layers "B.Cu" "B.Mask" "B.Paste")
			(net "GND")
		)
		(zone
			(layer "B.Cu")
			(hatch none 0.5)
			(connect_pads
				(clearance 0)
			)
			(min_thickness 0.25)
			(keepout
				(tracks not_allowed)
				(vias allowed)
				(pads allowed)
				(copperpour not_allowed)
				(footprints allowed)
			)
			(placement
				(enabled no)
				(sheetname "")
			)
			(fill
				(thermal_gap 0.5)
				(thermal_bridge_width 0.5)
				(island_removal_mode 0)
			)
			(polygon
				(pts
					(xy 408.965146 -21.599652) (xy 408.965146 -22.107652) (xy 409.346146 -22.107652) (xy 409.346146 -21.599652)
				)
			)
		)
		(zone
			(layer "B.Cu")
			(hatch none 0.5)
			(connect_pads
				(clearance 0)
			)
			(min_thickness 0.25)
			(keepout
				(tracks allowed)
				(vias not_allowed)
				(pads allowed)
				(copperpour not_allowed)
				(footprints allowed)
			)
			(placement
				(enabled no)
				(sheetname "")
			)
			(fill
				(thermal_gap 0.5)
				(thermal_bridge_width 0.5)
				(island_removal_mode 0)
			)
			(polygon
				(pts
					(xy 409.346146 -21.599652) (xy 409.346146 -22.107652) (xy 408.965146 -22.107652) (xy 408.965146 -21.599652)
				)
			)
		)
	)
)
